# BASEBOARD_FAB2 (Tioga Pass) — schematic netlist excerpt (pin names and nets, part order shuffled) for the footprints in the layout excerpt that follows; sources: Cadence DE-HDL packaged netlist, KiCad conversion of Wiwynn_Tioga_Pass_MB.brd

R9G14  RES  20.0 1% CHIP  pkg 0402  page 167 : A = SMB_SENSOR_BMC_STBY_LVC3_SCL ; B = SMB_SENSOR_STBY_LVC3_SCL
R7G25  RES  68.1K 1% EMPTY  pkg 0402  page 216 : A = VR_PVDDQ_ABC_PH1_OCSET ; B = GND
R7G21  RES  0.0 5% CHIP  pkg 0402  page 189 : A = JTAG_TDO ; B = JTAG_TDO_R

(kicad_pcb
	(version 20260206)
	(generator "pcbnew")
	(generator_version "10.0")
	(general
		(thickness 1.6)
		(legacy_teardrops no)
	)
	(paper "A4")
	(title_block
		(title "Wiwynn_Tioga_Pass_MB.brd")
		(comment 1 "Tioga Pass / footprints 939-941 of 4770")
	)
	(layers
		(0 "F.Cu" signal "TOP")
		(4 "In1.Cu" signal "L2GND")
		(6 "In2.Cu" signal "L3")
		(8 "In3.Cu" signal "L4GND")
		(10 "In4.Cu" signal "L5")
		(12 "In5.Cu" signal "L6GND")
		(14 "In6.Cu" signal "L7VCC")
		(16 "In7.Cu" signal "L8VCC")
		(18 "In8.Cu" signal "L9GND")
		(20 "In9.Cu" signal "L10")
		(22 "In10.Cu" signal "L11GND")
		(24 "In11.Cu" signal "L12")
		(26 "In12.Cu" signal "L13GND")
		(2 "B.Cu" signal "BOTTOM")
		(9 "F.Adhes" user "F.Adhesive")
		(11 "B.Adhes" user "B.Adhesive")
		(13 "F.Paste" user "Package Geometry/Pastemask Top")
		(15 "B.Paste" user "Package Geometry/Pastemask Bottom")
		(5 "F.SilkS" user "Ref Des/Silkscreen Top")
		(7 "B.SilkS" user "Ref Des/Silkscreen Bottom")
		(1 "F.Mask" user "Board Geometry/Soldermask Top")
		(3 "B.Mask" user "Board Geometry/Soldermask Bottom")
		(17 "Dwgs.User" user "User.Drawings")
		(19 "Cmts.User" user "User.Comments")
		(21 "Eco1.User" user "User.Eco1")
		(23 "Eco2.User" user "User.Eco2")
		(25 "Edge.Cuts" user "Board Geometry/Outline")
		(27 "Margin" user)
		(31 "F.CrtYd" user "Package Geometry/Place Bound Top")
		(29 "B.CrtYd" user "Package Geometry/Place Bound Bottom")
		(35 "F.Fab" user "Ref Des/Assembly Top")
		(33 "B.Fab" user "Ref Des/Assembly Bottom")
	)
	(footprint ""
		(layer "F.Cu")
		(at 352.5012 -11.1506 -90)
		(property "Reference" "R7G25"
			(at 0 0 270)
			(layer "F.SilkS")
			(hide yes)
			(effects
				(font
					(size 1.27 1.27)
				)
			)
		)
		(property "Value" ""
			(at 0 0 270)
			(layer "F.Fab")
			(effects
				(font
					(size 1.27 1.27)
				)
			)
		)
		(duplicate_pad_numbers_are_jumpers no)
		(fp_poly
			(pts
				(xy -0.2794 -0.1016) (xy 0.2794 -0.1016) (xy 0.2794 0.9906) (xy -0.2794 0.9906)
			)
			(stroke
				(width 0)
				(type default)
			)
			(fill no)
			(layer "F.CrtYd")
		)
		(fp_line
			(start -0.2794 0.9906)
			(end 0.2794 0.9906)
			(stroke
				(width 0.1)
				(type default)
			)
			(layer "F.Fab")
		)
		(fp_line
			(start 0.2794 0.9906)
			(end 0.2794 -0.1016)
			(stroke
				(width 0.1)
				(type default)
			)
			(layer "F.Fab")
		)
		(fp_line
			(start -0.2794 -0.1016)
			(end -0.2794 0.9906)
			(stroke
				(width 0.1)
				(type default)
			)
			(layer "F.Fab")
		)
		(fp_line
			(start 0.2794 -0.1016)
			(end -0.2794 -0.1016)
			(stroke
				(width 0.1)
				(type default)
			)
			(layer "F.Fab")
		)
		(pad "1" smd rect
			(at 0 0 270)
			(size 0.508 0.508)
			(layers "F.Cu" "F.Mask" "F.Paste")
			(net "VR_PVDDQ_ABC_PH1_OCSET")
		)
		(pad "2" smd rect
			(at 0 0.889 270)
			(size 0.508 0.508)
			(layers "F.Cu" "F.Mask" "F.Paste")
			(net "GND")
		)
		(zone
			(layer "F.Cu")
			(hatch none 0.5)
			(connect_pads
				(clearance 0)
			)
			(min_thickness 0.25)
			(keepout
				(tracks not_allowed)
				(vias allowed)
				(pads allowed)
				(copperpour not_allowed)
				(footprints allowed)
			)
			(placement
				(enabled no)
				(sheetname "")
			)
			(fill
				(thermal_gap 0.5)
				(thermal_bridge_width 0.5)
				(island_removal_mode 0)
			)
			(polygon
				(pts
					(xy 351.8662 -11.4046) (xy 351.8662 -10.8966) (xy 352.2472 -10.8966) (xy 352.2472 -11.4046)
				)
			)
		)
		(zone
			(layer "F.Cu")
			(hatch none 0.5)
			(connect_pads
				(clearance 0)
			)
			(min_thickness 0.25)
			(keepout
				(tracks allowed)
				(vias not_allowed)
				(pads allowed)
				(copperpour not_allowed)
				(footprints allowed)
			)
			(placement
				(enabled no)
				(sheetname "")
			)
			(fill
				(thermal_gap 0.5)
				(thermal_bridge_width 0.5)
				(island_removal_mode 0)
			)
			(polygon
				(pts
					(xy 352.2472 -11.4046) (xy 352.2472 -10.8966) (xy 351.8662 -10.8966) (xy 351.8662 -11.4046)
				)
			)
		)
	)
	(footprint ""
		(layer "F.Cu")
		(at 419.3032 -18.7452)
		(property "Reference" "R9G14"
			(at 0 0 0)
			(layer "F.SilkS")
			(hide yes)
			(effects
				(font
					(size 1.27 1.27)
				)
			)
		)
		(property "Value" ""
			(at 0 0 0)
			(layer "F.Fab")
			(effects
				(font
					(size 1.27 1.27)
				)
			)
		)
		(duplicate_pad_numbers_are_jumpers no)
		(fp_poly
			(pts
				(xy -0.2794 -0.1016) (xy 0.2794 -0.1016) (xy 0.2794 0.9906) (xy -0.2794 0.9906)
			)
			(stroke
				(width 0)
				(type default)
			)
			(fill no)
			(layer "F.CrtYd")
		)
		(fp_line
			(start -0.2794 -0.1016)
			(end -0.2794 0.9906)
			(stroke
				(width 0.1)
				(type default)
			)
			(layer "F.Fab")
		)
		(fp_line
			(start -0.2794 0.9906)
			(end 0.2794 0.9906)
			(stroke
				(width 0.1)
				(type default)
			)
			(layer "F.Fab")
		)
		(fp_line
			(start 0.2794 -0.1016)
			(end -0.2794 -0.1016)
			(stroke
				(width 0.1)
				(type default)
			)
			(layer "F.Fab")
		)
		(fp_line
			(start 0.2794 0.9906)
			(end 0.2794 -0.1016)
			(stroke
				(width 0.1)
				(type default)
			)
			(layer "F.Fab")
		)
		(pad "1" smd rect
			(at 0 0)
			(size 0.508 0.508)
			(layers "F.Cu" "F.Mask" "F.Paste")
			(net "SMB_SENSOR_BMC_STBY_LVC3_SCL")
		)
		(pad "2" smd rect
			(at 0 0.889)
			(size 0.508 0.508)
			(layers "F.Cu" "F.Mask" "F.Paste")
			(net "SMB_SENSOR_STBY_LVC3_SCL")
		)
		(zone
			(layer "F.Cu")
			(hatch none 0.5)
			(connect_pads
				(clearance 0)
			)
			(min_thickness 0.25)
			(keepout
				(tracks allowed)
				(vias not_allowed)
				(pads allowed)
				(copperpour not_allowed)
				(footprints allowed)
			)
			(placement
				(enabled no)
				(sheetname "")
			)
			(fill
				(thermal_gap 0.5)
				(thermal_bridge_width 0.5)
				(island_removal_mode 0)
			)
			(polygon
				(pts
					(xy 419.0492 -18.4912) (xy 419.5572 -18.4912) (xy 419.5572 -18.1102) (xy 419.0492 -18.1102)
				)
			)
		)
		(zone
			(layer "F.Cu")
			(hatch none 0.5)
			(connect_pads
				(clearance 0)
			)
			(min_thickness 0.25)
			(keepout
				(tracks not_allowed)
				(vias allowed)
				(pads allowed)
				(copperpour not_allowed)
				(footprints allowed)
			)
			(placement
				(enabled no)
				(sheetname "")
			)
			(fill
				(thermal_gap 0.5)
				(thermal_bridge_width 0.5)
				(island_removal_mode 0)
			)
			(polygon
				(pts
					(xy 419.0492 -18.1102) (xy 419.5572 -18.1102) (xy 419.5572 -18.4912) (xy 419.0492 -18.4912)
				)
			)
		)
	)
	(footprint ""
		(layer "F.Cu")
		(at 383.286 1.651 90)
		(property "Reference" "R7G21"
			(at 0 0 90)
			(layer "F.SilkS")
			(hide yes)
			(effects
				(font
					(size 1.27 1.27)
				)
			)
		)
		(property "Value" ""
			(at 0 0 90)
			(layer "F.Fab")
			(effects
				(font
					(size 1.27 1.27)
				)
			)
		)
		(duplicate_pad_numbers_are_jumpers no)
		(fp_poly
			(pts
				(xy -0.2794 -0.1016) (xy 0.2794 -0.1016) (xy 0.2794 0.9906) (xy -0.2794 0.9906)
			)
			(stroke
				(width 0)
				(type default)
			)
			(fill no)
			(layer "F.CrtYd")
		)
		(fp_line
			(start 0.2794 -0.1016)
			(end -0.2794 -0.1016)
			(stroke
				(width 0.1)
				(type default)
			)
			(layer "F.Fab")
		)
		(fp_line
			(start -0.2794 -0.1016)
			(end -0.2794 0.9906)
			(stroke
				(width 0.1)
				(type default)
			)
			(layer "F.Fab")
		)
		(fp_line
			(start 0.2794 0.9906)
			(end 0.2794 -0.1016)
			(stroke
				(width 0.1)
				(type default)
			)
			(layer "F.Fab")
		)
		(fp_line
			(start -0.2794 0.9906)
			(end 0.2794 0.9906)
			(stroke
				(width 0.1)
				(type default)
			)
			(layer "F.Fab")
		)
		(pad "1" smd rect
			(at 0 0 90)
			(size 0.508 0.508)
			(layers "F.Cu" "F.Mask" "F.Paste")
			(net "JTAG_TDO")
		)
		(pad "2" smd rect
			(at 0 0.889 90)
			(size 0.508 0.508)
			(layers "F.Cu" "F.Mask" "F.Paste")
			(net "JTAG_TDO_R")
		)
		(zone
			(layer "F.Cu")
			(hatch none 0.5)
			(connect_pads
				(clearance 0)
			)
			(min_thickness 0.25)
			(keepout
				(tracks allowed)
				(vias not_allowed)
				(pads allowed)
				(copperpour not_allowed)
				(footprints allowed)
			)
			(placement
				(enabled no)
				(sheetname "")
			)
			(fill
				(thermal_gap 0.5)
				(thermal_bridge_width 0.5)
				(island_removal_mode 0)
			)
			(polygon
				(pts
					(xy 383.54 1.905) (xy 383.54 1.397) (xy 383.921 1.397) (xy 383.921 1.905)
				)
			)
		)
		(zone
			(layer "F.Cu")
			(hatch none 0.5)
			(connect_pads
				(clearance 0)
			)
			(min_thickness 0.25)
			(keepout
				(tracks not_allowed)
				(vias allowed)
				(pads allowed)
				(copperpour not_allowed)
				(footprints allowed)
			)
			(placement
				(enabled no)
				(sheetname "")
			)
			(fill
				(thermal_gap 0.5)
				(thermal_bridge_width 0.5)
				(island_removal_mode 0)
			)
			(polygon
				(pts
					(xy 383.921 1.905) (xy 383.921 1.397) (xy 383.54 1.397) (xy 383.54 1.905)
				)
			)
		)
	)
)
